# T6G (Grand Teton) — schematic netlist excerpt (pin names and nets, part order shuffled) for the footprints in the layout excerpt that follows; sources: Cadence DE-HDL packaged netlist, KiCad conversion of 04192023_DAF0TMB3IC0_F0TG_MB_C_brd_V02_OCP.brd

R6311  Q_RES  0 5% CHIP  pkg 0402LF  page 178 : A = SMB_USB_CPU0_HUB1_SDA ; B = USB_HUB2_TI_OVERCUR1_MRP_PROG_FUNC4
C5009  Q_CAP  1000PF 50V 5% X7R  pkg 0402  page 207 : A = PVDD11_S3_P0_PMALERT ; B = GND
R596  Q_RES  0 5% CHIP  pkg 0201LF  page 276 : A = CLK_100M_RETIMER_CPU0_P0_R_DN ; B = CLK_100M_RETIMER_CPU0_P0_DN

(kicad_pcb
	(version 20260206)
	(generator "pcbnew")
	(generator_version "10.0")
	(general
		(thickness 1.6)
		(legacy_teardrops no)
	)
	(paper "A4")
	(title_block
		(title "04192023_DAF0TMB3IC0_F0TG_MB_C_brd_V02_OCP.brd")
		(comment 1 "Grand Teton / footprints 3397-3399 of 8354")
	)
	(layers
		(0 "F.Cu" signal "TOP")
		(4 "In1.Cu" signal "GND")
		(6 "In2.Cu" signal "IN1")
		(8 "In3.Cu" signal "GND1")
		(10 "In4.Cu" signal "IN2")
		(12 "In5.Cu" signal "GND2")
		(14 "In6.Cu" signal "IN3")
		(16 "In7.Cu" signal "GND3")
		(18 "In8.Cu" signal "VCC")
		(20 "In9.Cu" signal "VCC1")
		(22 "In10.Cu" signal "GND4")
		(24 "In11.Cu" signal "IN4")
		(26 "In12.Cu" signal "GND5")
		(28 "In13.Cu" signal "IN5")
		(30 "In14.Cu" signal "GND6")
		(32 "In15.Cu" signal "IN6")
		(34 "In16.Cu" signal "GND7")
		(2 "B.Cu" signal "BOTTOM")
		(9 "F.Adhes" user "F.Adhesive")
		(11 "B.Adhes" user "B.Adhesive")
		(13 "F.Paste" user "Package Geometry/Pastemask Top")
		(15 "B.Paste" user "Package Geometry/Pastemask Bottom")
		(5 "F.SilkS" user "Ref Des/Silkscreen Top")
		(7 "B.SilkS" user "Ref Des/Silkscreen Bottom")
		(1 "F.Mask" user "Board Geometry/Soldermask Top")
		(3 "B.Mask" user "Board Geometry/Soldermask Bottom")
		(17 "Dwgs.User" user "User.Drawings")
		(19 "Cmts.User" user "User.Comments")
		(21 "Eco1.User" user "User.Eco1")
		(23 "Eco2.User" user "User.Eco2")
		(25 "Edge.Cuts" user "Board Geometry/Outline")
		(27 "Margin" user)
		(31 "F.CrtYd" user "Package Geometry/Place Bound Top")
		(29 "B.CrtYd" user "Package Geometry/Place Bound Bottom")
		(35 "F.Fab" user "Ref Des/Assembly Top")
		(33 "B.Fab" user "Ref Des/Assembly Bottom")
	)
	(footprint ""
		(layer "F.Cu")
		(at 414.316418 -367.796064 180)
		(property "Reference" "C5009"
			(at 0 0 180)
			(layer "F.SilkS")
			(hide yes)
			(effects
				(font
					(size 1.27 1.27)
				)
			)
		)
		(property "Value" ""
			(at 0 0 180)
			(layer "F.Fab")
			(effects
				(font
					(size 1.27 1.27)
				)
			)
		)
		(duplicate_pad_numbers_are_jumpers no)
		(fp_line
			(start 0.7874 0.4064)
			(end -0.7874 0.4064)
			(stroke
				(width 0.1524)
				(type default)
			)
			(layer "F.SilkS")
		)
		(fp_line
			(start 0.7874 -0.4064)
			(end 0.7874 0.4064)
			(stroke
				(width 0.1524)
				(type default)
			)
			(layer "F.SilkS")
		)
		(fp_line
			(start -0.7874 0.4064)
			(end -0.7874 -0.4064)
			(stroke
				(width 0.1524)
				(type default)
			)
			(layer "F.SilkS")
		)
		(fp_line
			(start -0.7874 -0.4064)
			(end 0.7874 -0.4064)
			(stroke
				(width 0.1524)
				(type default)
			)
			(layer "F.SilkS")
		)
		(fp_line
			(start 0.67945 0.3048)
			(end 0.120396 0.3048)
			(stroke
				(width 0.1)
				(type default)
			)
			(layer "F.Fab")
		)
		(fp_line
			(start 0.67945 -0.3048)
			(end 0.67945 0.3048)
			(stroke
				(width 0.1)
				(type default)
			)
			(layer "F.Fab")
		)
		(fp_line
			(start 0.12065 -0.2794)
			(end 0.12065 -0.3048)
			(stroke
				(width 0.1)
				(type default)
			)
			(layer "F.Fab")
		)
		(fp_line
			(start 0.12065 -0.3048)
			(end 0.67945 -0.3048)
			(stroke
				(width 0.1)
				(type default)
			)
			(layer "F.Fab")
		)
		(fp_line
			(start 0.120396 0.3048)
			(end 0.120396 0.2794)
			(stroke
				(width 0.1)
				(type default)
			)
			(layer "F.Fab")
		)
		(fp_line
			(start 0.120396 0.2794)
			(end -0.12065 0.2794)
			(stroke
				(width 0.1)
				(type default)
			)
			(layer "F.Fab")
		)
		(fp_line
			(start -0.12065 0.3048)
			(end -0.67945 0.3048)
			(stroke
				(width 0.1)
				(type default)
			)
			(layer "F.Fab")
		)
		(fp_line
			(start -0.12065 0.2794)
			(end -0.12065 0.3048)
			(stroke
				(width 0.1)
				(type default)
			)
			(layer "F.Fab")
		)
		(fp_line
			(start -0.12065 -0.2794)
			(end 0.12065 -0.2794)
			(stroke
				(width 0.1)
				(type default)
			)
			(layer "F.Fab")
		)
		(fp_line
			(start -0.12065 -0.305054)
			(end -0.12065 -0.2794)
			(stroke
				(width 0.1)
				(type default)
			)
			(layer "F.Fab")
		)
		(fp_line
			(start -0.67945 0.3048)
			(end -0.67945 -0.305054)
			(stroke
				(width 0.1)
				(type default)
			)
			(layer "F.Fab")
		)
		(fp_line
			(start -0.67945 -0.305054)
			(end -0.12065 -0.305054)
			(stroke
				(width 0.1)
				(type default)
			)
			(layer "F.Fab")
		)
		(pad "1" smd circle
			(at -0.40005 0 180)
			(size 0 0)
			(layers "F.Cu" "F.Mask" "F.Paste")
			(net "PVDD11_S3_P0_PMALERT")
		)
		(pad "2" smd circle
			(at 0.40005 0 180)
			(size 0 0)
			(layers "F.Cu" "F.Mask" "F.Paste")
			(net "GND")
		)
	)
	(footprint ""
		(layer "F.Cu")
		(at 298.527724 -395.333474)
		(property "Reference" "R596"
			(at 0 0 0)
			(layer "F.SilkS")
			(hide yes)
			(effects
				(font
					(size 1.27 1.27)
				)
			)
		)
		(property "Value" ""
			(at 0 0 0)
			(layer "F.Fab")
			(effects
				(font
					(size 1.27 1.27)
				)
			)
		)
		(duplicate_pad_numbers_are_jumpers no)
		(fp_line
			(start -0.32512 -0.175006)
			(end 0.32512 -0.175006)
			(stroke
				(width 0.1)
				(type default)
			)
			(layer "F.Fab")
		)
		(fp_line
			(start -0.32512 0.175006)
			(end -0.32512 -0.175006)
			(stroke
				(width 0.1)
				(type default)
			)
			(layer "F.Fab")
		)
		(fp_line
			(start 0.32512 -0.175006)
			(end 0.32512 0.175006)
			(stroke
				(width 0.1)
				(type default)
			)
			(layer "F.Fab")
		)
		(fp_line
			(start 0.32512 0.175006)
			(end -0.32512 0.175006)
			(stroke
				(width 0.1)
				(type default)
			)
			(layer "F.Fab")
		)
		(pad "1" smd rect
			(at -0.2667 0)
			(size 0.3048 0.381)
			(layers "F.Cu" "F.Mask" "F.Paste")
			(net "CLK_100M_RETIMER_CPU0_P0_R_DN")
		)
		(pad "2" smd rect
			(at 0.2667 0 180)
			(size 0.3048 0.381)
			(layers "F.Cu" "F.Mask" "F.Paste")
			(net "CLK_100M_RETIMER_CPU0_P0_DN")
		)
	)
	(footprint ""
		(layer "F.Cu")
		(at 107.517946 -52.86248 -90)
		(property "Reference" "R6311"
			(at 0 0 270)
			(layer "F.SilkS")
			(hide yes)
			(effects
				(font
					(size 1.27 1.27)
				)
			)
		)
		(property "Value" ""
			(at 0 0 270)
			(layer "F.Fab")
			(effects
				(font
					(size 1.27 1.27)
				)
			)
		)
		(duplicate_pad_numbers_are_jumpers no)
		(fp_line
			(start -0.7874 0.4064)
			(end -0.7874 -0.4064)
			(stroke
				(width 0.1524)
				(type default)
			)
			(layer "F.SilkS")
		)
		(fp_line
			(start 0.7874 0.4064)
			(end -0.7874 0.4064)
			(stroke
				(width 0.1524)
				(type default)
			)
			(layer "F.SilkS")
		)
		(fp_line
			(start -0.7874 -0.4064)
			(end 0.7874 -0.4064)
			(stroke
				(width 0.1524)
				(type default)
			)
			(layer "F.SilkS")
		)
		(fp_line
			(start 0.7874 -0.4064)
			(end 0.7874 0.4064)
			(stroke
				(width 0.1524)
				(type default)
			)
			(layer "F.SilkS")
		)
		(fp_line
			(start -0.67945 0.3048)
			(end -0.67945 -0.305054)
			(stroke
				(width 0.1)
				(type default)
			)
			(layer "F.Fab")
		)
		(fp_line
			(start -0.12065 0.3048)
			(end -0.67945 0.3048)
			(stroke
				(width 0.1)
				(type default)
			)
			(layer "F.Fab")
		)
		(fp_line
			(start 0.120396 0.3048)
			(end 0.120396 0.2794)
			(stroke
				(width 0.1)
				(type default)
			)
			(layer "F.Fab")
		)
		(fp_line
			(start 0.67945 0.3048)
			(end 0.120396 0.3048)
			(stroke
				(width 0.1)
				(type default)
			)
			(layer "F.Fab")
		)
		(fp_line
			(start -0.12065 0.2794)
			(end -0.12065 0.3048)
			(stroke
				(width 0.1)
				(type default)
			)
			(layer "F.Fab")
		)
		(fp_line
			(start 0.120396 0.2794)
			(end -0.12065 0.2794)
			(stroke
				(width 0.1)
				(type default)
			)
			(layer "F.Fab")
		)
		(fp_line
			(start -0.12065 -0.2794)
			(end 0.12065 -0.2794)
			(stroke
				(width 0.1)
				(type default)
			)
			(layer "F.Fab")
		)
		(fp_line
			(start 0.12065 -0.2794)
			(end 0.12065 -0.3048)
			(stroke
				(width 0.1)
				(type default)
			)
			(layer "F.Fab")
		)
		(fp_line
			(start 0.12065 -0.3048)
			(end 0.67945 -0.3048)
			(stroke
				(width 0.1)
				(type default)
			)
			(layer "F.Fab")
		)
		(fp_line
			(start 0.67945 -0.3048)
			(end 0.67945 0.3048)
			(stroke
				(width 0.1)
				(type default)
			)
			(layer "F.Fab")
		)
		(fp_line
			(start -0.67945 -0.305054)
			(end -0.12065 -0.305054)
			(stroke
				(width 0.1)
				(type default)
			)
			(layer "F.Fab")
		)
		(fp_line
			(start -0.12065 -0.305054)
			(end -0.12065 -0.2794)
			(stroke
				(width 0.1)
				(type default)
			)
			(layer "F.Fab")
		)
		(pad "1" smd circle
			(at -0.40005 0 270)
			(size 0 0)
			(layers "F.Cu" "F.Mask" "F.Paste")
			(net "SMB_USB_CPU0_HUB1_SDA")
		)
		(pad "2" smd circle
			(at 0.40005 0 270)
			(size 0 0)
			(layers "F.Cu" "F.Mask" "F.Paste")
			(net "USB_HUB2_TI_OVERCUR1_MRP_PROG_FUNC4")
		)
	)
)
